FILE_TYPE=LIBRARY_PARTS;
primitive 'M25PE16','M25PE16_SM';
  pin
    'S_N':
      PIN_NUMBER='(1)';
      INPUT_LOAD='(-0.01,0.01)';
    'RESET_N':
      PIN_NUMBER='(7)';
      INPUT_LOAD='(-0.01,0.01)';
    'C':
      PIN_NUMBER='(6)';
      INPUT_LOAD='(-0.01,0.01)';
    'DQ0':
      PIN_NUMBER='(5)';
      INPUT_LOAD='(-0.01,0.01)';
    'DQ1':
      PIN_NUMBER='(2)';
      OUTPUT_LOAD='(1.0,-1.0)';
    'VCC':
      PIN_NUMBER='(8)';
      PINUSE='POWER';
      NO_LOAD_CHECK='Both';
      NO_IO_CHECK='Both';
      NO_ASSERT_CHECK='TRUE';
      NO_DIR_CHECK='TRUE';
      ALLOW_CONNECT='TRUE';
    'VSS':
      PIN_NUMBER='(4)';
      PINUSE='GROUND';
      NO_LOAD_CHECK='Both';
      NO_IO_CHECK='Both';
      NO_ASSERT_CHECK='TRUE';
      NO_DIR_CHECK='TRUE';
      ALLOW_CONNECT='TRUE';
    'W_N':
      PIN_NUMBER='(3)';
      INPUT_LOAD='(-0.01,0.01)';
  end_pin;
  body
    PART_NAME='M25PE16';
    PHYS_DES_PREFIX='U';
  end_body;
end_primitive;

END.
